G04*
G04 #@! TF.GenerationSoftware,Altium Limited,Altium Designer,23.0.1 (38)*
G04*
G04 Layer_Color=8388736*
%FSLAX25Y25*%
%MOIN*%
G70*
G04*
G04 #@! TF.SameCoordinates,C48E81DB-6E20-4E2D-80E6-7C5AFAA1A21F*
G04*
G04*
G04 #@! TF.FilePolarity,Positive*
G04*
G01*
G75*
%ADD15C,0.00787*%
D15*
X684744Y-25492D02*
X686909D01*
X684744Y-29626D02*
Y-25492D01*
Y-29626D02*
X686909D01*
Y-25492D01*
X550394Y-235827D02*
X580315D01*
Y-253937D02*
Y-235827D01*
X550394Y-253937D02*
X580315D01*
X550394D02*
Y-235827D01*
X599756Y-262748D02*
X626228D01*
Y-289220D02*
Y-262748D01*
X599756Y-289220D02*
X626228D01*
X599756D02*
Y-262748D01*
X684252Y-323425D02*
X688189D01*
X684252D02*
Y-321457D01*
X688189D01*
Y-323425D02*
Y-321457D01*
X669193Y-325295D02*
X676476D01*
X669193D02*
Y-321161D01*
X676476D01*
Y-325295D02*
Y-321161D01*
X669193Y-317815D02*
X676476D01*
X669193D02*
Y-313681D01*
X676476D01*
Y-317815D02*
Y-313681D01*
X684252Y-316732D02*
X688189D01*
X684252D02*
Y-314764D01*
X688189D01*
Y-316732D02*
Y-314764D01*
X700197Y-108169D02*
Y-69784D01*
X679823Y-107283D02*
X707776D01*
Y-70669D01*
X679823D02*
X707776D01*
X679823Y-107283D02*
Y-70669D01*
X679528Y-59055D02*
X691339D01*
Y-47244D01*
X679528D02*
X691339D01*
X679528Y-59055D02*
Y-47244D01*
X670866Y-100787D02*
X674016D01*
X670866Y-107087D02*
Y-100787D01*
Y-107087D02*
X674016D01*
Y-100787D01*
X666142Y-111614D02*
Y-109646D01*
X662205D02*
X666142D01*
X662205Y-111614D02*
Y-109646D01*
Y-111614D02*
X666142D01*
X691732Y-67126D02*
Y-65158D01*
Y-67126D02*
X695669D01*
Y-65158D01*
X691732D02*
X695669D01*
X671752Y-95571D02*
Y-93405D01*
X667618D02*
X671752D01*
X667618Y-95571D02*
Y-93405D01*
Y-95571D02*
X671752D01*
X678445Y-33957D02*
X680610D01*
Y-29823D01*
X678445D02*
X680610D01*
X678445Y-33957D02*
Y-29823D01*
X685630Y-39764D02*
X687598D01*
Y-35827D01*
X685630D02*
X687598D01*
X685630Y-39764D02*
Y-35827D01*
X693110Y-39900D02*
X695079D01*
Y-35963D01*
X693110D02*
X695079D01*
X693110Y-39900D02*
Y-35963D01*
X613583Y-97441D02*
Y-89173D01*
Y-97441D02*
X620669D01*
Y-89173D01*
X613583D02*
X620669D01*
X625591Y-94291D02*
Y-92323D01*
Y-94291D02*
X629528D01*
Y-92323D01*
X625591D02*
X629528D01*
X580709Y-97441D02*
Y-89173D01*
Y-97441D02*
X587795D01*
Y-89173D01*
X580709D02*
X587795D01*
X596260Y-94095D02*
X598228D01*
Y-90158D01*
X596260D02*
X598228D01*
X596260Y-94095D02*
Y-90158D01*
X415807Y-134055D02*
Y-115551D01*
Y-134055D02*
X431437D01*
Y-115551D01*
X415807D02*
X431437D01*
X407776Y-126279D02*
X411909D01*
X407776Y-133563D02*
Y-126279D01*
Y-133563D02*
X411909D01*
Y-126279D01*
X434547Y-125886D02*
X438681D01*
X434547Y-133169D02*
Y-125886D01*
Y-133169D02*
X438681D01*
Y-125886D01*
X244291Y-124803D02*
X252559D01*
Y-117717D01*
X244291D02*
X252559D01*
X244291Y-124803D02*
Y-117717D01*
X249410Y-112598D02*
X251378D01*
Y-108661D01*
X249410D02*
X251378D01*
X249410Y-112598D02*
Y-108661D01*
X408746Y-115818D02*
X410714D01*
X408746Y-119755D02*
Y-115818D01*
Y-119755D02*
X410714D01*
Y-115818D01*
X435630Y-116921D02*
X437598D01*
X435630Y-120858D02*
Y-116921D01*
Y-120858D02*
X437598D01*
Y-116921D01*
X548032Y-280906D02*
X551968D01*
X548032D02*
Y-278937D01*
X551968D01*
Y-280906D02*
Y-278937D01*
X603299Y-228984D02*
Y-202512D01*
Y-228984D02*
X629772D01*
Y-202512D01*
X603299D02*
X629772D01*
X651181Y-168504D02*
X669291D01*
X651181Y-198425D02*
Y-168504D01*
Y-198425D02*
X669291D01*
Y-168504D01*
X682377Y-187148D02*
X684346D01*
Y-183211D01*
X682377D02*
X684346D01*
X682377Y-187148D02*
Y-183211D01*
X627165Y-236614D02*
Y-231102D01*
Y-236614D02*
X634252D01*
Y-231102D01*
X627165D02*
X634252D01*
X648425Y-221260D02*
X652362D01*
X648425Y-228346D02*
Y-221260D01*
Y-228346D02*
X652362D01*
Y-221260D01*
X563386Y-222638D02*
Y-220669D01*
X559449D02*
X563386D01*
X559449Y-222638D02*
Y-220669D01*
Y-222638D02*
X563386D01*
X593307Y-238386D02*
Y-236417D01*
X589370D02*
X593307D01*
X589370Y-238386D02*
Y-236417D01*
Y-238386D02*
X593307D01*
X597441Y-236417D02*
X600984D01*
X597441Y-243110D02*
Y-236417D01*
Y-243110D02*
X600984D01*
Y-236417D01*
X620276Y-235236D02*
Y-231693D01*
X613583D02*
X620276D01*
X613583Y-235236D02*
Y-231693D01*
Y-235236D02*
X620276D01*
X680905Y-205254D02*
X682874D01*
X680905Y-209191D02*
Y-205254D01*
Y-209191D02*
X682874D01*
Y-205254D01*
X672047Y-191339D02*
X679134D01*
Y-177953D01*
X672047D02*
X679134D01*
X672047Y-191339D02*
Y-177953D01*
X665945Y-205512D02*
X667913D01*
X665945Y-209449D02*
Y-205512D01*
Y-209449D02*
X667913D01*
Y-205512D01*
X677126Y-238189D02*
Y-218504D01*
X661457D02*
X677126D01*
X661457Y-238189D02*
Y-218504D01*
Y-238189D02*
X677126D01*
X632283Y-200394D02*
Y-182283D01*
X602362D02*
X632283D01*
X602362Y-200394D02*
Y-182283D01*
Y-200394D02*
X632283D01*
X592913Y-194882D02*
X599213D01*
Y-182283D01*
X592913D02*
X599213D01*
X592913Y-194882D02*
Y-182283D01*
X672441Y-203937D02*
X676378D01*
X672441Y-211024D02*
Y-203937D01*
Y-211024D02*
X676378D01*
Y-203937D01*
X583465Y-194882D02*
X589764D01*
Y-182283D01*
X583465D02*
X589764D01*
X583465Y-194882D02*
Y-182283D01*
X559154Y-197539D02*
X561319D01*
X559154Y-201673D02*
Y-197539D01*
Y-201673D02*
X561319D01*
Y-197539D01*
X552559Y-225197D02*
X554528D01*
Y-221260D01*
X552559D02*
X554528D01*
X552559Y-225197D02*
Y-221260D01*
X561614Y-216535D02*
X563583D01*
Y-212598D01*
X561614D02*
X563583D01*
X561614Y-216535D02*
Y-212598D01*
X583760Y-148327D02*
Y-120177D01*
X608366D01*
Y-148327D02*
Y-120177D01*
X583760Y-148327D02*
X608366D01*
X648401Y-155445D02*
Y-115945D01*
X699901D01*
Y-155445D02*
Y-115945D01*
X648401Y-155445D02*
X699901D01*
X578957Y-181535D02*
Y-157047D01*
X550965D02*
X578957D01*
X550965Y-181535D02*
Y-157047D01*
Y-181535D02*
X578957D01*
X616142Y-298819D02*
Y-293307D01*
Y-298819D02*
X623228D01*
Y-293307D01*
X616142D02*
X623228D01*
X603740Y-297441D02*
Y-293898D01*
X597047D02*
X603740D01*
X597047Y-297441D02*
Y-293898D01*
Y-297441D02*
X603740D01*
X561943Y-293504D02*
Y-291535D01*
X558006D02*
X561943D01*
X558006Y-293504D02*
Y-291535D01*
Y-293504D02*
X561943D01*
X551968Y-292717D02*
Y-290748D01*
X548032D02*
X551968D01*
X548032Y-292717D02*
Y-290748D01*
Y-292717D02*
X551968D01*
X590748Y-289370D02*
X592717D01*
X590748Y-293307D02*
Y-289370D01*
Y-293307D02*
X592717D01*
Y-289370D01*
X546752Y-257579D02*
X548917D01*
X546752Y-261713D02*
Y-257579D01*
Y-261713D02*
X548917D01*
Y-257579D01*
X575787Y-293504D02*
Y-289961D01*
X569095D02*
X575787D01*
X569095Y-293504D02*
Y-289961D01*
Y-293504D02*
X575787D01*
X591339Y-259842D02*
X597638D01*
Y-247244D01*
X591339D02*
X597638D01*
X591339Y-259842D02*
Y-247244D01*
X602362Y-260236D02*
X608661D01*
Y-247638D01*
X602362D02*
X608661D01*
X602362Y-260236D02*
Y-247638D01*
X657480Y-272047D02*
Y-264961D01*
Y-272047D02*
X670866D01*
Y-264961D01*
X657480D02*
X670866D01*
X643701Y-278937D02*
Y-276969D01*
X639764D02*
X643701D01*
X639764Y-278937D02*
Y-276969D01*
Y-278937D02*
X643701D01*
X662598Y-277362D02*
Y-275394D01*
Y-277362D02*
X666535D01*
Y-275394D01*
X662598D02*
X666535D01*
X663412Y-253287D02*
Y-251319D01*
Y-253287D02*
X667348D01*
Y-251319D01*
X663412D02*
X667348D01*
X661811Y-262205D02*
Y-258268D01*
Y-262205D02*
X668898D01*
Y-258268D01*
X661811D02*
X668898D01*
X628346Y-263386D02*
Y-245276D01*
Y-263386D02*
X658268D01*
Y-245276D01*
X628346D02*
X658268D01*
X669252Y-309842D02*
Y-290158D01*
X653583D02*
X669252D01*
X653583Y-309842D02*
Y-290158D01*
Y-309842D02*
X669252D01*
X641339Y-291339D02*
X645276D01*
X641339Y-298425D02*
Y-291339D01*
Y-298425D02*
X645276D01*
Y-291339D01*
X541339Y-118543D02*
X561024D01*
X541339Y-134213D02*
Y-118543D01*
Y-134213D02*
X561024D01*
Y-118543D01*
X538189Y-135827D02*
Y-131890D01*
X531102D02*
X538189D01*
X531102Y-135827D02*
Y-131890D01*
Y-135827D02*
X538189D01*
X496850Y-110827D02*
Y-108858D01*
Y-110827D02*
X500787D01*
Y-108858D01*
X496850D02*
X500787D01*
X478543Y-114764D02*
X499409D01*
X478543Y-130118D02*
Y-114764D01*
Y-130118D02*
X499409D01*
Y-114764D01*
X44390Y-43701D02*
X50098D01*
Y-35039D01*
X44390D02*
X50098D01*
X44390Y-43701D02*
Y-35039D01*
X121555Y-45276D02*
X127264D01*
Y-36614D01*
X121555D02*
X127264D01*
X121555Y-45276D02*
Y-36614D01*
X663386Y-59547D02*
Y-53839D01*
Y-59547D02*
X672047D01*
Y-53839D01*
X663386D02*
X672047D01*
X609842Y-56791D02*
Y-51083D01*
X601181D02*
X609842D01*
X601181Y-56791D02*
Y-51083D01*
Y-56791D02*
X609842D01*
X611122Y-180807D02*
Y-156201D01*
Y-180807D02*
X639272D01*
Y-156201D01*
X611122D02*
X639272D01*
X38583Y8465D02*
X42126D01*
Y15157D01*
X38583D02*
X42126D01*
X38583Y8465D02*
Y15157D01*
X31693Y8465D02*
X35236D01*
Y15157D01*
X31693D02*
X35236D01*
X31693Y8465D02*
Y15157D01*
X24803Y8465D02*
X28346D01*
Y15157D01*
X24803D02*
X28346D01*
X24803Y8465D02*
Y15157D01*
X45472Y8465D02*
X49016D01*
Y15157D01*
X45472D02*
X49016D01*
X45472Y8465D02*
Y15157D01*
X76575Y-112008D02*
Y-108465D01*
Y-112008D02*
X83268D01*
Y-108465D01*
X76575D02*
X83268D01*
X73917Y-121949D02*
X77658D01*
X73917Y-128839D02*
Y-121949D01*
Y-128839D02*
X77658D01*
Y-121949D01*
X665354Y-26476D02*
Y-20768D01*
Y-26476D02*
X674016D01*
Y-20768D01*
X665354D02*
X674016D01*
X617520Y-24360D02*
Y-18651D01*
X608858D02*
X617520D01*
X608858Y-24360D02*
Y-18651D01*
Y-24360D02*
X617520D01*
X86713Y-90009D02*
X92421D01*
X86713Y-98671D02*
Y-90009D01*
Y-98671D02*
X92421D01*
Y-90009D01*
X120177Y-71702D02*
X125886D01*
X120177Y-80364D02*
Y-71702D01*
Y-80364D02*
X125886D01*
Y-71702D01*
X510630Y-119734D02*
X520866D01*
Y-129970D02*
Y-119734D01*
X510630Y-129970D02*
X520866D01*
X510630D02*
Y-119734D01*
X454921Y-122687D02*
X466339D01*
X454921Y-128986D02*
Y-122687D01*
Y-128986D02*
X466339D01*
Y-122687D01*
M02*
